# TIMECARD (Time Appliance Project (Time Card)) — schematic netlist excerpt (pin names and nets, part order shuffled) for the footprints in the layout excerpt that follows; sources: Cadence DE-HDL packaged netlist, KiCad conversion of R4006-B0001-02_R01.brd

R344  RESISTOR  4.7KOHM 1%  pkg SMC_0402R_H016  page 16 : \1\ = SN_EEPROM_WP ; \2\ = SG
R321  RESISTOR  33OHM 1%  pkg SMC_0402R_H016  page 26 : \1\ = FPGA_M_RGB_LED_I2C_SDA ; \2\ = R_RGB_LED_I2C_SDA

(kicad_pcb
	(version 20260206)
	(generator "pcbnew")
	(generator_version "10.0")
	(general
		(thickness 1.6)
		(legacy_teardrops no)
	)
	(paper "A4")
	(title_block
		(title "timecard-production-celestica-r4006 — R4006-B0001-02_R01.brd")
		(comment 1 "Time Appliance Project (Time Card) / footprints 922-923 of 1113")
	)
	(layers
		(0 "F.Cu" signal "TOP")
		(4 "In1.Cu" signal "L02_GND1")
		(6 "In2.Cu" signal "L03_SIG1")
		(8 "In3.Cu" signal "L04_GND2")
		(10 "In4.Cu" signal "L05_VCC1")
		(12 "In5.Cu" signal "L06_VCC2")
		(14 "In6.Cu" signal "L07_GND3")
		(16 "In7.Cu" signal "L08_SIG2")
		(18 "In8.Cu" signal "L09_GND4")
		(2 "B.Cu" signal "BOTTOM")
		(9 "F.Adhes" user "F.Adhesive")
		(11 "B.Adhes" user "B.Adhesive")
		(13 "F.Paste" user "Package Geometry/Pastemask Top")
		(15 "B.Paste" user "Package Geometry/Pastemask Bottom")
		(5 "F.SilkS" user "Ref Des/Silkscreen Top")
		(7 "B.SilkS" user "Ref Des/Silkscreen Bottom")
		(1 "F.Mask" user "Board Geometry/Soldermask Top")
		(3 "B.Mask" user "Board Geometry/Soldermask Bottom")
		(17 "Dwgs.User" user "User.Drawings")
		(19 "Cmts.User" user "User.Comments")
		(21 "Eco1.User" user "User.Eco1")
		(23 "Eco2.User" user "User.Eco2")
		(25 "Edge.Cuts" user "Board Geometry/Outline")
		(27 "Margin" user)
		(31 "F.CrtYd" user "Package Geometry/Place Bound Top")
		(29 "B.CrtYd" user "Package Geometry/Place Bound Bottom")
		(35 "F.Fab" user "Ref Des/Assembly Top")
		(33 "B.Fab" user "Ref Des/Assembly Bottom")
	)
	(footprint ""
		(layer "B.Cu")
		(at 111.125 -103.251)
		(property "Reference" "R321"
			(at 0.381 -3.26263 0)
			(unlocked yes)
			(layer "B.SilkS")
			(effects
				(font
					(size 0.7874 0.5842)
					(thickness 0.1524)
				)
				(justify mirror)
			)
		)
		(property "Value" "VAL*"
			(at -0.02032 2.13233 0)
			(unlocked yes)
			(layer "B.Fab")
			(hide yes)
			(effects
				(font
					(size 0.7874 0.5842)
					(thickness 0.1524)
				)
				(justify mirror)
			)
		)
		(property "Tolerance" "TOL*"
			(at -0.044704 3.05435 0)
			(unlocked yes)
			(layer "Cmts.User")
			(hide yes)
			(effects
				(font
					(size 0.7874 0.5842)
					(thickness 0.1524)
				)
				(justify mirror)
			)
		)
		(property "User Part Number" "PARTNUM*"
			(at -0.02032 4.024884 0)
			(unlocked yes)
			(layer "Cmts.User")
			(hide yes)
			(effects
				(font
					(size 0.7874 0.5842)
					(thickness 0.1524)
				)
				(justify mirror)
			)
		)
		(property "Device Type" "RESISTOR-G155-133R0-01,33OHM,1%"
			(at -0.008382 1.210564 0)
			(unlocked yes)
			(layer "B.Fab")
			(hide yes)
			(effects
				(font
					(size 0.7874 0.5842)
					(thickness 0.1524)
				)
				(justify mirror)
			)
		)
		(duplicate_pad_numbers_are_jumpers no)
		(fp_line
			(start -1.143 -0.5588)
			(end 1.143 -0.5588)
			(stroke
				(width 0.1)
				(type default)
			)
			(layer "B.SilkS")
		)
		(fp_line
			(start -1.143 0.5588)
			(end -1.143 -0.5588)
			(stroke
				(width 0.1)
				(type default)
			)
			(layer "B.SilkS")
		)
		(fp_line
			(start 1.143 -0.5588)
			(end 1.143 0.5588)
			(stroke
				(width 0.1)
				(type default)
			)
			(layer "B.SilkS")
		)
		(fp_line
			(start 1.143 0.5588)
			(end -1.143 0.5588)
			(stroke
				(width 0.1)
				(type default)
			)
			(layer "B.SilkS")
		)
		(fp_poly
			(pts
				(xy 1.143 0.5588) (xy -1.143 0.5588) (xy -1.143 -0.5588) (xy 1.143 -0.5588)
			)
			(stroke
				(width 0)
				(type default)
			)
			(fill no)
			(layer "B.CrtYd")
		)
		(fp_line
			(start -0.508 -0.3048)
			(end 0.508 -0.3048)
			(stroke
				(width 0.1)
				(type default)
			)
			(layer "B.Fab")
		)
		(fp_line
			(start -0.508 0.3048)
			(end -0.508 -0.3048)
			(stroke
				(width 0.1)
				(type default)
			)
			(layer "B.Fab")
		)
		(fp_line
			(start 0.508 -0.3048)
			(end 0.508 0.3048)
			(stroke
				(width 0.1)
				(type default)
			)
			(layer "B.Fab")
		)
		(fp_line
			(start 0.508 0.3048)
			(end -0.508 0.3048)
			(stroke
				(width 0.1)
				(type default)
			)
			(layer "B.Fab")
		)
		(pad "1" smd rect
			(at 0.5334 0 180)
			(size 0.7112 0.6096)
			(layers "B.Cu" "B.Mask" "B.Paste")
			(net "FPGA_M_RGB_LED_I2C_SDA")
		)
		(pad "2" smd rect
			(at -0.5334 0 180)
			(size 0.7112 0.6096)
			(layers "B.Cu" "B.Mask" "B.Paste")
			(net "R_RGB_LED_I2C_SDA")
		)
		(zone
			(layer "B.Cu")
			(hatch none 0.5)
			(connect_pads
				(clearance 0)
			)
			(min_thickness 0.25)
			(keepout
				(tracks not_allowed)
				(vias allowed)
				(pads allowed)
				(copperpour not_allowed)
				(footprints allowed)
			)
			(placement
				(enabled no)
				(sheetname "")
			)
			(fill
				(thermal_gap 0.5)
				(thermal_bridge_width 0.5)
				(island_removal_mode 0)
			)
			(polygon
				(pts
					(xy 111.2012 -102.9462) (xy 111.2012 -103.5558) (xy 111.0488 -103.5558) (xy 111.0488 -102.9462)
				)
			)
		)
		(zone
			(layer "B.Cu")
			(hatch none 0.5)
			(connect_pads
				(clearance 0)
			)
			(min_thickness 0.25)
			(keepout
				(tracks allowed)
				(vias not_allowed)
				(pads allowed)
				(copperpour not_allowed)
				(footprints allowed)
			)
			(placement
				(enabled no)
				(sheetname "")
			)
			(fill
				(thermal_gap 0.5)
				(thermal_bridge_width 0.5)
				(island_removal_mode 0)
			)
			(polygon
				(pts
					(xy 111.2012 -102.9462) (xy 111.2012 -103.5558) (xy 111.0488 -103.5558) (xy 111.0488 -102.9462)
				)
			)
		)
	)
	(footprint ""
		(layer "B.Cu")
		(at 26.8986 -18.2372)
		(property "Reference" "R344"
			(at -0.2286 1.38557 0)
			(unlocked yes)
			(layer "B.SilkS")
			(effects
				(font
					(size 0.7874 0.5842)
					(thickness 0.1524)
				)
				(justify mirror)
			)
		)
		(property "Value" "VAL*"
			(at -0.02032 2.13233 0)
			(unlocked yes)
			(layer "B.Fab")
			(hide yes)
			(effects
				(font
					(size 0.7874 0.5842)
					(thickness 0.1524)
				)
				(justify mirror)
			)
		)
		(property "Tolerance" "TOL*"
			(at -0.044704 3.05435 0)
			(unlocked yes)
			(layer "Cmts.User")
			(hide yes)
			(effects
				(font
					(size 0.7874 0.5842)
					(thickness 0.1524)
				)
				(justify mirror)
			)
		)
		(property "User Part Number" "PARTNUM*"
			(at -0.02032 4.024884 0)
			(unlocked yes)
			(layer "Cmts.User")
			(hide yes)
			(effects
				(font
					(size 0.7874 0.5842)
					(thickness 0.1524)
				)
				(justify mirror)
			)
		)
		(property "Device Type" "RESISTOR-G155-14701-01,4.7KOHMA"
			(at -0.008382 1.210564 0)
			(unlocked yes)
			(layer "B.Fab")
			(hide yes)
			(effects
				(font
					(size 0.7874 0.5842)
					(thickness 0.1524)
				)
				(justify mirror)
			)
		)
		(duplicate_pad_numbers_are_jumpers no)
		(fp_line
			(start -1.143 -0.5588)
			(end 1.143 -0.5588)
			(stroke
				(width 0.1)
				(type default)
			)
			(layer "B.SilkS")
		)
		(fp_line
			(start -1.143 0.5588)
			(end -1.143 -0.5588)
			(stroke
				(width 0.1)
				(type default)
			)
			(layer "B.SilkS")
		)
		(fp_line
			(start 1.143 -0.5588)
			(end 1.143 0.5588)
			(stroke
				(width 0.1)
				(type default)
			)
			(layer "B.SilkS")
		)
		(fp_line
			(start 1.143 0.5588)
			(end -1.143 0.5588)
			(stroke
				(width 0.1)
				(type default)
			)
			(layer "B.SilkS")
		)
		(fp_rect
			(start 1.143 -0.5588)
			(end -1.143 0.5588)
			(stroke
				(width 0)
				(type default)
			)
			(fill no)
			(layer "B.CrtYd")
		)
		(fp_line
			(start -0.508 -0.3048)
			(end 0.508 -0.3048)
			(stroke
				(width 0.1)
				(type default)
			)
			(layer "B.Fab")
		)
		(fp_line
			(start -0.508 0.3048)
			(end -0.508 -0.3048)
			(stroke
				(width 0.1)
				(type default)
			)
			(layer "B.Fab")
		)
		(fp_line
			(start 0.508 -0.3048)
			(end 0.508 0.3048)
			(stroke
				(width 0.1)
				(type default)
			)
			(layer "B.Fab")
		)
		(fp_line
			(start 0.508 0.3048)
			(end -0.508 0.3048)
			(stroke
				(width 0.1)
				(type default)
			)
			(layer "B.Fab")
		)
		(pad "1" smd rect
			(at 0.5334 0 180)
			(size 0.7112 0.6096)
			(layers "B.Cu" "B.Mask" "B.Paste")
			(net "SN_EEPROM_WP")
		)
		(pad "2" smd rect
			(at -0.5334 0 180)
			(size 0.7112 0.6096)
			(layers "B.Cu" "B.Mask" "B.Paste")
			(net "SG")
		)
		(zone
			(layer "B.Cu")
			(hatch none 0.5)
			(connect_pads
				(clearance 0)
			)
			(min_thickness 0.25)
			(keepout
				(tracks allowed)
				(vias not_allowed)
				(pads allowed)
				(copperpour not_allowed)
				(footprints allowed)
			)
			(placement
				(enabled no)
				(sheetname "")
			)
			(fill
				(thermal_gap 0.5)
				(thermal_bridge_width 0.5)
				(island_removal_mode 0)
			)
			(polygon
				(pts
					(xy 26.9748 -18.542) (xy 26.8224 -18.542) (xy 26.8224 -17.9324) (xy 26.9748 -17.9324)
				)
			)
		)
	)
)
